# S9S_MB_2U (Grand Teton) — schematic netlist excerpt (pin names and nets, part order shuffled) for the footprints in the layout excerpt that follows; sources: Cadence DE-HDL packaged netlist, KiCad conversion of 03242023_DA0F0TMBIJ0_F0T_Motherboard_J_brd_V01_OCP.brd

C1995  Q_CAP_DIFFBUS  DIFF BUS_0.22UF 6.3V 20% X6S  pkg C0201  page 181 : \1\ = P3E_PCH_E1S_TX_DP<0> ; \2\ = P3E_PCH_E1S_TX_C_DP<0>
C912  Q_CAP_DIFFBUS  DIFF BUS_0.22UF 6.3V 20% X6S  pkg C0201  page 173 : \1\ = P5E_CPU0_PE0_TX_C_DN<10> ; \2\ = P5E_CPU0_PE0_TX_DN<10>
R1593  Q_RES  4.7K 1% CHIP  pkg 0402LF  page 155 : A = P3V3_AUX ; B = OCP_SFF_PWRBRK_BUFF_N

(kicad_pcb
	(version 20260206)
	(generator "pcbnew")
	(generator_version "10.0")
	(general
		(thickness 1.6)
		(legacy_teardrops no)
	)
	(paper "A4")
	(title_block
		(title "03242023_DA0F0TMBIJ0_F0T_Motherboard_J_brd_V01_OCP.brd")
		(comment 1 "Grand Teton / footprints 2132-2134 of 6105")
	)
	(layers
		(0 "F.Cu" signal "TOP")
		(4 "In1.Cu" signal "GND")
		(6 "In2.Cu" signal "IN1")
		(8 "In3.Cu" signal "GND1")
		(10 "In4.Cu" signal "IN2")
		(12 "In5.Cu" signal "GND2")
		(14 "In6.Cu" signal "IN3")
		(16 "In7.Cu" signal "GND3")
		(18 "In8.Cu" signal "VCC")
		(20 "In9.Cu" signal "VCC1")
		(22 "In10.Cu" signal "GND4")
		(24 "In11.Cu" signal "IN4")
		(26 "In12.Cu" signal "GND5")
		(28 "In13.Cu" signal "IN5")
		(30 "In14.Cu" signal "GND6")
		(32 "In15.Cu" signal "IN6")
		(34 "In16.Cu" signal "GND7")
		(2 "B.Cu" signal "BOTTOM")
		(9 "F.Adhes" user "F.Adhesive")
		(11 "B.Adhes" user "B.Adhesive")
		(13 "F.Paste" user "Package Geometry/Pastemask Top")
		(15 "B.Paste" user "Package Geometry/Pastemask Bottom")
		(5 "F.SilkS" user "Ref Des/Silkscreen Top")
		(7 "B.SilkS" user "Ref Des/Silkscreen Bottom")
		(1 "F.Mask" user "Board Geometry/Soldermask Top")
		(3 "B.Mask" user "Board Geometry/Soldermask Bottom")
		(17 "Dwgs.User" user "User.Drawings")
		(19 "Cmts.User" user "User.Comments")
		(21 "Eco1.User" user "User.Eco1")
		(23 "Eco2.User" user "User.Eco2")
		(25 "Edge.Cuts" user "Board Geometry/Outline")
		(27 "Margin" user)
		(31 "F.CrtYd" user "Package Geometry/Place Bound Top")
		(29 "B.CrtYd" user "Package Geometry/Place Bound Bottom")
		(35 "F.Fab" user "Ref Des/Assembly Top")
		(33 "B.Fab" user "Ref Des/Assembly Bottom")
	)
	(footprint ""
		(layer "F.Cu")
		(at 320.617088 -408.517344 -90)
		(property "Reference" "C912"
			(at 0 0 270)
			(layer "F.SilkS")
			(hide yes)
			(effects
				(font
					(size 1.27 1.27)
				)
			)
		)
		(property "Value" ""
			(at 0 0 270)
			(layer "F.Fab")
			(effects
				(font
					(size 1.27 1.27)
				)
			)
		)
		(duplicate_pad_numbers_are_jumpers no)
		(fp_line
			(start -0.299974 0.150114)
			(end -0.299974 -0.150114)
			(stroke
				(width 0.1)
				(type default)
			)
			(layer "F.Fab")
		)
		(fp_line
			(start 0.299974 0.150114)
			(end -0.299974 0.150114)
			(stroke
				(width 0.1)
				(type default)
			)
			(layer "F.Fab")
		)
		(fp_line
			(start -0.299974 -0.150114)
			(end 0.299974 -0.150114)
			(stroke
				(width 0.1)
				(type default)
			)
			(layer "F.Fab")
		)
		(fp_line
			(start 0.299974 -0.150114)
			(end 0.299974 0.150114)
			(stroke
				(width 0.1)
				(type default)
			)
			(layer "F.Fab")
		)
		(pad "1" smd rect
			(at -0.2667 0 270)
			(size 0.3048 0.381)
			(layers "F.Cu" "F.Mask" "F.Paste")
			(net "P5E_CPU0_PE0_TX_C_DN<10>")
		)
		(pad "2" smd rect
			(at 0.2667 0 270)
			(size 0.3048 0.381)
			(layers "F.Cu" "F.Mask" "F.Paste")
			(net "P5E_CPU0_PE0_TX_DN<10>")
		)
	)
	(footprint ""
		(layer "F.Cu")
		(at 392.119866 -31.185612 -90)
		(property "Reference" "R1593"
			(at 0 0 270)
			(layer "F.SilkS")
			(hide yes)
			(effects
				(font
					(size 1.27 1.27)
				)
			)
		)
		(property "Value" ""
			(at 0 0 270)
			(layer "F.Fab")
			(effects
				(font
					(size 1.27 1.27)
				)
			)
		)
		(duplicate_pad_numbers_are_jumpers no)
		(fp_line
			(start -0.7874 0.4064)
			(end -0.7874 -0.4064)
			(stroke
				(width 0.1524)
				(type default)
			)
			(layer "F.SilkS")
		)
		(fp_line
			(start 0.7874 0.4064)
			(end -0.7874 0.4064)
			(stroke
				(width 0.1524)
				(type default)
			)
			(layer "F.SilkS")
		)
		(fp_line
			(start -0.7874 -0.4064)
			(end 0.7874 -0.4064)
			(stroke
				(width 0.1524)
				(type default)
			)
			(layer "F.SilkS")
		)
		(fp_line
			(start 0.7874 -0.4064)
			(end 0.7874 0.4064)
			(stroke
				(width 0.1524)
				(type default)
			)
			(layer "F.SilkS")
		)
		(fp_line
			(start -0.67945 0.3048)
			(end -0.67945 -0.305054)
			(stroke
				(width 0.1)
				(type default)
			)
			(layer "F.Fab")
		)
		(fp_line
			(start -0.12065 0.3048)
			(end -0.67945 0.3048)
			(stroke
				(width 0.1)
				(type default)
			)
			(layer "F.Fab")
		)
		(fp_line
			(start 0.120396 0.3048)
			(end 0.120396 0.2794)
			(stroke
				(width 0.1)
				(type default)
			)
			(layer "F.Fab")
		)
		(fp_line
			(start 0.67945 0.3048)
			(end 0.120396 0.3048)
			(stroke
				(width 0.1)
				(type default)
			)
			(layer "F.Fab")
		)
		(fp_line
			(start -0.12065 0.2794)
			(end -0.12065 0.3048)
			(stroke
				(width 0.1)
				(type default)
			)
			(layer "F.Fab")
		)
		(fp_line
			(start 0.120396 0.2794)
			(end -0.12065 0.2794)
			(stroke
				(width 0.1)
				(type default)
			)
			(layer "F.Fab")
		)
		(fp_line
			(start -0.12065 -0.2794)
			(end 0.12065 -0.2794)
			(stroke
				(width 0.1)
				(type default)
			)
			(layer "F.Fab")
		)
		(fp_line
			(start 0.12065 -0.2794)
			(end 0.12065 -0.3048)
			(stroke
				(width 0.1)
				(type default)
			)
			(layer "F.Fab")
		)
		(fp_line
			(start 0.12065 -0.3048)
			(end 0.67945 -0.3048)
			(stroke
				(width 0.1)
				(type default)
			)
			(layer "F.Fab")
		)
		(fp_line
			(start 0.67945 -0.3048)
			(end 0.67945 0.3048)
			(stroke
				(width 0.1)
				(type default)
			)
			(layer "F.Fab")
		)
		(fp_line
			(start -0.67945 -0.305054)
			(end -0.12065 -0.305054)
			(stroke
				(width 0.1)
				(type default)
			)
			(layer "F.Fab")
		)
		(fp_line
			(start -0.12065 -0.305054)
			(end -0.12065 -0.2794)
			(stroke
				(width 0.1)
				(type default)
			)
			(layer "F.Fab")
		)
		(pad "1" smd circle
			(at -0.40005 0 270)
			(size 0 0)
			(layers "F.Cu" "F.Mask" "F.Paste")
			(net "P3V3_AUX")
		)
		(pad "2" smd circle
			(at 0.40005 0 270)
			(size 0 0)
			(layers "F.Cu" "F.Mask" "F.Paste")
			(net "OCP_SFF_PWRBRK_BUFF_N")
		)
	)
	(footprint ""
		(layer "F.Cu")
		(at 239.152684 -52.01285 180)
		(property "Reference" "C1995"
			(at 0 0 180)
			(layer "F.SilkS")
			(hide yes)
			(effects
				(font
					(size 1.27 1.27)
				)
			)
		)
		(property "Value" ""
			(at 0 0 180)
			(layer "F.Fab")
			(effects
				(font
					(size 1.27 1.27)
				)
			)
		)
		(duplicate_pad_numbers_are_jumpers no)
		(fp_line
			(start 0.299974 0.150114)
			(end -0.299974 0.150114)
			(stroke
				(width 0.1)
				(type default)
			)
			(layer "F.Fab")
		)
		(fp_line
			(start 0.299974 -0.150114)
			(end 0.299974 0.150114)
			(stroke
				(width 0.1)
				(type default)
			)
			(layer "F.Fab")
		)
		(fp_line
			(start -0.299974 0.150114)
			(end -0.299974 -0.150114)
			(stroke
				(width 0.1)
				(type default)
			)
			(layer "F.Fab")
		)
		(fp_line
			(start -0.299974 -0.150114)
			(end 0.299974 -0.150114)
			(stroke
				(width 0.1)
				(type default)
			)
			(layer "F.Fab")
		)
		(pad "1" smd rect
			(at -0.2667 0 180)
			(size 0.3048 0.381)
			(layers "F.Cu" "F.Mask" "F.Paste")
			(net "P3E_PCH_E1S_TX_DP<0>")
		)
		(pad "2" smd rect
			(at 0.2667 0 180)
			(size 0.3048 0.381)
			(layers "F.Cu" "F.Mask" "F.Paste")
			(net "P3E_PCH_E1S_TX_C_DP<0>")
		)
		(zone
			(layer "In1.Cu")
			(hatch none 0.5)
			(connect_pads
				(clearance 0)
			)
			(min_thickness 0.25)
			(keepout
				(tracks not_allowed)
				(vias allowed)
				(pads allowed)
				(copperpour not_allowed)
				(footprints allowed)
			)
			(placement
				(enabled no)
				(sheetname "")
			)
			(fill
				(thermal_gap 0.5)
				(thermal_bridge_width 0.5)
				(island_removal_mode 0)
			)
			(polygon
				(pts
					(arc
						(start 239.012984 -52.253134)
						(mid 239.066866 -52.230816)
						(end 239.089184 -52.176934)
					)
					(arc
						(start 239.089184 -51.846734)
						(mid 239.066866 -51.792852)
						(end 239.012984 -51.770534)
					)
					(arc
						(start 238.758984 -51.770534)
						(mid 238.705102 -51.792852)
						(end 238.682784 -51.846734)
					)
					(arc
						(start 238.682784 -52.176934)
						(mid 238.705102 -52.230816)
						(end 238.758984 -52.253134)
					)
				)
			)
		)
		(zone
			(layer "In1.Cu")
			(hatch none 0.5)
			(connect_pads
				(clearance 0)
			)
			(min_thickness 0.25)
			(keepout
				(tracks not_allowed)
				(vias allowed)
				(pads allowed)
				(copperpour not_allowed)
				(footprints allowed)
			)
			(placement
				(enabled no)
				(sheetname "")
			)
			(fill
				(thermal_gap 0.5)
				(thermal_bridge_width 0.5)
				(island_removal_mode 0)
			)
			(polygon
				(pts
					(arc
						(start 239.546384 -52.253134)
						(mid 239.600266 -52.230816)
						(end 239.622584 -52.176934)
					)
					(arc
						(start 239.622584 -51.846734)
						(mid 239.600266 -51.792852)
						(end 239.546384 -51.770534)
					)
					(arc
						(start 239.292384 -51.770534)
						(mid 239.238502 -51.792852)
						(end 239.216184 -51.846734)
					)
					(arc
						(start 239.216184 -52.176934)
						(mid 239.238502 -52.230816)
						(end 239.292384 -52.253134)
					)
				)
			)
		)
	)
)
